(kicad_pcb
	(version 20260206)
	(generator "pcbnew")
	(generator_version "10.0")
	(general
		(thickness 1.6)
		(legacy_teardrops no)
	)
	(paper "A4")
	(title_block
		(title "timecard-production-celestica-r4006 — R4006-B0001-02_R01.brd")
		(comment 1 "Time Appliance Project (Time Card) / footprints 463-468 of 1113")
	)
	(layers
		(0 "F.Cu" signal "TOP")
		(4 "In1.Cu" signal "L02_GND1")
		(6 "In2.Cu" signal "L03_SIG1")
		(8 "In3.Cu" signal "L04_GND2")
		(10 "In4.Cu" signal "L05_VCC1")
		(12 "In5.Cu" signal "L06_VCC2")
		(14 "In6.Cu" signal "L07_GND3")
		(16 "In7.Cu" signal "L08_SIG2")
		(18 "In8.Cu" signal "L09_GND4")
		(2 "B.Cu" signal "BOTTOM")
		(9 "F.Adhes" user "F.Adhesive")
		(11 "B.Adhes" user "B.Adhesive")
		(13 "F.Paste" user "Package Geometry/Pastemask Top")
		(15 "B.Paste" user "Package Geometry/Pastemask Bottom")
		(5 "F.SilkS" user "Ref Des/Silkscreen Top")
		(7 "B.SilkS" user "Ref Des/Silkscreen Bottom")
		(1 "F.Mask" user "Board Geometry/Soldermask Top")
		(3 "B.Mask" user "Board Geometry/Soldermask Bottom")
		(17 "Dwgs.User" user "User.Drawings")
		(19 "Cmts.User" user "User.Comments")
		(21 "Eco1.User" user "User.Eco1")
		(23 "Eco2.User" user "User.Eco2")
		(25 "Edge.Cuts" user "Board Geometry/Outline")
		(27 "Margin" user)
		(31 "F.CrtYd" user "Package Geometry/Place Bound Top")
		(29 "B.CrtYd" user "Package Geometry/Place Bound Bottom")
		(35 "F.Fab" user "Ref Des/Assembly Top")
		(33 "B.Fab" user "Ref Des/Assembly Bottom")
	)
	(footprint ""
		(layer "F.Cu")
		(at 84.836 -71.501 90)
		(property "Reference" "J17"
			(at 3.38963 -0.762 0)
			(unlocked yes)
			(layer "F.SilkS")
			(effects
				(font
					(size 0.7874 0.5842)
					(thickness 0.1524)
				)
			)
		)
		(property "Value" ""
			(at 0 0 90)
			(layer "F.Fab")
			(effects
				(font
					(size 1.27 1.27)
				)
			)
		)
		(property "Device Type" "CONN_HDR_2X2_M_S_SMT-G200-1068A"
			(at 0.069088 6.518656 90)
			(unlocked yes)
			(layer "F.Fab")
			(hide yes)
			(effects
				(font
					(size 0.7874 0.5842)
					(thickness 0.000001)
				)
			)
		)
		(property "User Part Number" "PARTNUM*"
			(at 0.069088 7.712456 90)
			(unlocked yes)
			(layer "Cmts.User")
			(hide yes)
			(effects
				(font
					(size 0.7874 0.5842)
					(thickness 0.000001)
				)
			)
		)
		(duplicate_pad_numbers_are_jumpers no)
		(fp_line
			(start 2.589022 -4.637024)
			(end 2.589022 4.637024)
			(stroke
				(width 0.1)
				(type default)
			)
			(layer "F.SilkS")
		)
		(fp_line
			(start -2.589022 -4.637024)
			(end 2.589022 -4.637024)
			(stroke
				(width 0.1)
				(type default)
			)
			(layer "F.SilkS")
		)
		(fp_line
			(start 2.589022 4.637024)
			(end -2.589022 4.637024)
			(stroke
				(width 0.1)
				(type default)
			)
			(layer "F.SilkS")
		)
		(fp_line
			(start -2.589022 4.637024)
			(end -2.589022 -4.637024)
			(stroke
				(width 0.1)
				(type default)
			)
			(layer "F.SilkS")
		)
		(fp_rect
			(start -2.843022 4.891024)
			(end 2.843022 -4.891024)
			(stroke
				(width 0)
				(type default)
			)
			(fill no)
			(layer "F.CrtYd")
		)
		(fp_line
			(start 2.335022 -2.439924)
			(end -2.335022 -2.439924)
			(stroke
				(width 0.1)
				(type default)
			)
			(layer "F.Fab")
		)
		(fp_line
			(start -2.335022 -2.439924)
			(end -2.335022 2.439924)
			(stroke
				(width 0.1)
				(type default)
			)
			(layer "F.Fab")
		)
		(fp_line
			(start 2.335022 2.439924)
			(end 2.335022 -2.439924)
			(stroke
				(width 0.1)
				(type default)
			)
			(layer "F.Fab")
		)
		(fp_line
			(start -2.335022 2.439924)
			(end 2.335022 2.439924)
			(stroke
				(width 0.1)
				(type default)
			)
			(layer "F.Fab")
		)
		(fp_text user "4"
			(at 2.11963 -5.4991 0)
			(unlocked yes)
			(layer "F.SilkS")
			(effects
				(font
					(size 0.7874 0.5842)
					(thickness 0.1524)
				)
				(justify left)
			)
		)
		(fp_text user "2"
			(at -0.29337 -5.4991 0)
			(unlocked yes)
			(layer "F.SilkS")
			(effects
				(font
					(size 0.7874 0.5842)
					(thickness 0.1524)
				)
				(justify left)
			)
		)
		(fp_text user "3"
			(at 3.13563 3.0099 0)
			(unlocked yes)
			(layer "F.SilkS")
			(effects
				(font
					(size 0.7874 0.5842)
					(thickness 0.1524)
				)
				(justify left)
			)
		)
		(fp_text user "1"
			(at -0.42037 4.7879 0)
			(unlocked yes)
			(layer "F.SilkS")
			(effects
				(font
					(size 0.7874 0.5842)
					(thickness 0.1524)
				)
				(justify left)
			)
		)
		(fp_text user "4"
			(at 1.109218 -3.767074 0)
			(unlocked yes)
			(layer "F.Fab")
			(effects
				(font
					(size 0.7874 0.5842)
					(thickness 0.1524)
				)
				(justify left)
			)
		)
		(fp_text user "2"
			(at -1.667002 -3.7338 0)
			(unlocked yes)
			(layer "F.Fab")
			(effects
				(font
					(size 0.7874 0.5842)
					(thickness 0.1524)
				)
				(justify left)
			)
		)
		(fp_text user "3"
			(at 1.26111 2.939542 0)
			(unlocked yes)
			(layer "F.Fab")
			(effects
				(font
					(size 0.7874 0.5842)
					(thickness 0.1524)
				)
				(justify left)
			)
		)
		(fp_text user "1"
			(at -1.38049 2.939542 0)
			(unlocked yes)
			(layer "F.Fab")
			(effects
				(font
					(size 0.7874 0.5842)
					(thickness 0.1524)
				)
				(justify left)
			)
		)
		(pad "1" smd rect
			(at -1.27 2.605024 90)
			(size 1.27 3.556)
			(layers "F.Cu" "F.Mask" "F.Paste")
			(net "SN_EEPROM_WP")
		)
		(pad "2" smd rect
			(at -1.27 -2.605024 90)
			(size 1.27 3.556)
			(layers "F.Cu" "F.Mask" "F.Paste")
			(net "SG")
		)
		(pad "3" smd rect
			(at 1.27 2.605024 90)
			(size 1.27 3.556)
			(layers "F.Cu" "F.Mask" "F.Paste")
			(net "SEC_EEPROM_WP")
		)
		(pad "4" smd rect
			(at 1.27 -2.605024 90)
			(size 1.27 3.556)
			(layers "F.Cu" "F.Mask" "F.Paste")
			(net "SG")
		)
	)
	(footprint ""
		(layer "F.Cu")
		(at 44.069 -130.429)
		(property "Reference" "SP65"
			(at 0 0 0)
			(layer "F.SilkS")
			(hide yes)
			(effects
				(font
					(size 1.27 1.27)
				)
			)
		)
		(property "Value" ""
			(at 0 0 0)
			(layer "F.Fab")
			(effects
				(font
					(size 1.27 1.27)
				)
			)
		)
		(duplicate_pad_numbers_are_jumpers no)
	)
	(footprint ""
		(layer "F.Cu")
		(at 135.6614 -99.1108)
		(property "Reference" "R9"
			(at -2.5654 -0.29083 0)
			(unlocked yes)
			(layer "F.SilkS")
			(effects
				(font
					(size 0.7874 0.5842)
					(thickness 0.1524)
				)
			)
		)
		(property "Value" "VAL*"
			(at 0.0508 2.549906 0)
			(unlocked yes)
			(layer "F.Fab")
			(hide yes)
			(effects
				(font
					(size 0.7874 0.5842)
					(thickness 0.1524)
				)
			)
		)
		(property "Device Type" "RESISTOR-G156-049R9-01,49.9OHMA"
			(at 0.0254 1.584706 0)
			(unlocked yes)
			(layer "F.Fab")
			(hide yes)
			(effects
				(font
					(size 0.7874 0.5842)
					(thickness 0.1524)
				)
			)
		)
		(property "User Part Number" "PARTNUM*"
			(at 0.0762 4.480306 0)
			(unlocked yes)
			(layer "Cmts.User")
			(hide yes)
			(effects
				(font
					(size 0.7874 0.5842)
					(thickness 0.1524)
				)
			)
		)
		(property "Tolerance" "TOL*"
			(at 0.0508 3.515106 0)
			(unlocked yes)
			(layer "Cmts.User")
			(hide yes)
			(effects
				(font
					(size 0.7874 0.5842)
					(thickness 0.1524)
				)
			)
		)
		(duplicate_pad_numbers_are_jumpers no)
		(fp_line
			(start -1.3208 -0.7112)
			(end 1.3208 -0.7112)
			(stroke
				(width 0.1)
				(type default)
			)
			(layer "F.SilkS")
		)
		(fp_line
			(start -1.3208 0.7112)
			(end -1.3208 -0.7112)
			(stroke
				(width 0.1)
				(type default)
			)
			(layer "F.SilkS")
		)
		(fp_line
			(start 1.3208 -0.7112)
			(end 1.3208 0.7112)
			(stroke
				(width 0.1)
				(type default)
			)
			(layer "F.SilkS")
		)
		(fp_line
			(start 1.3208 0.7112)
			(end -1.3208 0.7112)
			(stroke
				(width 0.1)
				(type default)
			)
			(layer "F.SilkS")
		)
		(fp_rect
			(start -1.3208 0.7112)
			(end 1.3208 -0.7112)
			(stroke
				(width 0)
				(type default)
			)
			(fill no)
			(layer "F.CrtYd")
		)
		(fp_line
			(start -0.8128 -0.4572)
			(end 0.8128 -0.4572)
			(stroke
				(width 0.1)
				(type default)
			)
			(layer "F.Fab")
		)
		(fp_line
			(start -0.8128 0.4572)
			(end -0.8128 -0.4572)
			(stroke
				(width 0.1)
				(type default)
			)
			(layer "F.Fab")
		)
		(fp_line
			(start 0.8128 -0.4572)
			(end 0.8128 0.4572)
			(stroke
				(width 0.1)
				(type default)
			)
			(layer "F.Fab")
		)
		(fp_line
			(start 0.8128 0.4572)
			(end -0.8128 0.4572)
			(stroke
				(width 0.1)
				(type default)
			)
			(layer "F.Fab")
		)
		(pad "1" smd rect
			(at -0.6858 0)
			(size 0.762 0.8636)
			(layers "F.Cu" "F.Mask" "F.Paste")
			(net "XP12R0V_IN")
		)
		(pad "2" smd rect
			(at 0.6858 0)
			(size 0.762 0.8636)
			(layers "F.Cu" "F.Mask" "F.Paste")
			(net "XP12R0V_A_AVIN")
		)
		(zone
			(layer "F.Cu")
			(hatch none 0.5)
			(connect_pads
				(clearance 0)
			)
			(min_thickness 0.25)
			(keepout
				(tracks allowed)
				(vias not_allowed)
				(pads allowed)
				(copperpour not_allowed)
				(footprints allowed)
			)
			(placement
				(enabled no)
				(sheetname "")
			)
			(fill
				(thermal_gap 0.5)
				(thermal_bridge_width 0.5)
				(island_removal_mode 0)
			)
			(polygon
				(pts
					(xy 135.509 -98.6536) (xy 135.8138 -98.6536) (xy 135.8138 -99.568) (xy 135.509 -99.568)
				)
			)
		)
	)
	(footprint ""
		(layer "F.Cu")
		(at 126.0602 -70.5358 180)
		(property "Reference" "C191"
			(at 0.0762 3.33883 0)
			(unlocked yes)
			(layer "F.SilkS")
			(effects
				(font
					(size 0.7874 0.5842)
					(thickness 0.1524)
				)
			)
		)
		(property "Value" "VAL*"
			(at 0.193548 2.13614 180)
			(unlocked yes)
			(layer "F.Fab")
			(hide yes)
			(effects
				(font
					(size 0.7874 0.5842)
					(thickness 0.1524)
				)
			)
		)
		(property "Tolerance" "TOL*"
			(at 0.216154 3.1496 180)
			(unlocked yes)
			(layer "Cmts.User")
			(hide yes)
			(effects
				(font
					(size 0.7874 0.5842)
					(thickness 0.1524)
				)
			)
		)
		(property "Device Type" "CAPACITOR-G104-0B103-EK,0.01UFA"
			(at 0.184404 1.180592 180)
			(unlocked yes)
			(layer "F.Fab")
			(hide yes)
			(effects
				(font
					(size 0.7874 0.5842)
					(thickness 0.1524)
				)
			)
		)
		(property "User Part Number" "PARTNUM*"
			(at 0.216154 4.185666 180)
			(unlocked yes)
			(layer "Cmts.User")
			(hide yes)
			(effects
				(font
					(size 0.7874 0.5842)
					(thickness 0.1524)
				)
			)
		)
		(duplicate_pad_numbers_are_jumpers no)
		(fp_line
			(start 0.671322 0.4445)
			(end -0.671322 0.4445)
			(stroke
				(width 0.1)
				(type default)
			)
			(layer "F.SilkS")
		)
		(fp_line
			(start 0.671322 -0.4445)
			(end 0.671322 0.4445)
			(stroke
				(width 0.1)
				(type default)
			)
			(layer "F.SilkS")
		)
		(fp_line
			(start -0.671322 0.4445)
			(end -0.671322 -0.4445)
			(stroke
				(width 0.1)
				(type default)
			)
			(layer "F.SilkS")
		)
		(fp_line
			(start -0.671322 -0.4445)
			(end 0.671322 -0.4445)
			(stroke
				(width 0.1)
				(type default)
			)
			(layer "F.SilkS")
		)
		(fp_rect
			(start -0.671322 0.4445)
			(end 0.671322 -0.4445)
			(stroke
				(width 0)
				(type default)
			)
			(fill no)
			(layer "F.CrtYd")
		)
		(fp_line
			(start 0.31496 0.1651)
			(end 0.31496 -0.1651)
			(stroke
				(width 0.1)
				(type default)
			)
			(layer "F.Fab")
		)
		(fp_line
			(start 0.31496 -0.1651)
			(end -0.31496 -0.1651)
			(stroke
				(width 0.1)
				(type default)
			)
			(layer "F.Fab")
		)
		(fp_line
			(start -0.31496 0.1651)
			(end 0.31496 0.1651)
			(stroke
				(width 0.1)
				(type default)
			)
			(layer "F.Fab")
		)
		(fp_line
			(start -0.31496 -0.1651)
			(end -0.31496 0.1651)
			(stroke
				(width 0.1)
				(type default)
			)
			(layer "F.Fab")
		)
		(pad "1" smd rect
			(at -0.264922 0 180)
			(size 0.3048 0.381)
			(layers "F.Cu" "F.Mask" "F.Paste")
			(net "XP1R8V_SS")
		)
		(pad "2" smd rect
			(at 0.264922 0 180)
			(size 0.3048 0.381)
			(layers "F.Cu" "F.Mask" "F.Paste")
			(net "SG")
		)
		(zone
			(layer "F.Cu")
			(hatch none 0.5)
			(connect_pads
				(clearance 0)
			)
			(min_thickness 0.25)
			(keepout
				(tracks allowed)
				(vias not_allowed)
				(pads allowed)
				(copperpour not_allowed)
				(footprints allowed)
			)
			(placement
				(enabled no)
				(sheetname "")
			)
			(fill
				(thermal_gap 0.5)
				(thermal_bridge_width 0.5)
				(island_removal_mode 0)
			)
			(polygon
				(pts
					(xy 126.172722 -70.7263) (xy 125.947678 -70.7263) (xy 125.947678 -70.3453) (xy 126.172722 -70.3453)
				)
			)
		)
	)
	(footprint ""
		(layer "F.Cu")
		(at 13.589 -22.987 -90)
		(property "Reference" "R157"
			(at 0.635 3.51663 90)
			(unlocked yes)
			(layer "F.SilkS")
			(effects
				(font
					(size 0.7874 0.5842)
					(thickness 0.1524)
				)
			)
		)
		(property "Value" "VAL*"
			(at 0.02032 2.13233 270)
			(unlocked yes)
			(layer "F.Fab")
			(hide yes)
			(effects
				(font
					(size 0.7874 0.5842)
					(thickness 0.1524)
				)
			)
		)
		(property "Tolerance" "TOL*"
			(at 0.044704 3.05435 270)
			(unlocked yes)
			(layer "Cmts.User")
			(hide yes)
			(effects
				(font
					(size 0.7874 0.5842)
					(thickness 0.1524)
				)
			)
		)
		(property "User Part Number" "PARTNUM*"
			(at 0.02032 4.024884 270)
			(unlocked yes)
			(layer "Cmts.User")
			(hide yes)
			(effects
				(font
					(size 0.7874 0.5842)
					(thickness 0.1524)
				)
			)
		)
		(property "Device Type" "RESISTOR-G155-11000-01,100OHM,A"
			(at 0.008382 1.210564 270)
			(unlocked yes)
			(layer "F.Fab")
			(hide yes)
			(effects
				(font
					(size 0.7874 0.5842)
					(thickness 0.1524)
				)
			)
		)
		(duplicate_pad_numbers_are_jumpers no)
		(fp_line
			(start -1.143 0.5588)
			(end 1.143 0.5588)
			(stroke
				(width 0.1)
				(type default)
			)
			(layer "F.SilkS")
		)
		(fp_line
			(start 1.143 0.5588)
			(end 1.143 -0.5588)
			(stroke
				(width 0.1)
				(type default)
			)
			(layer "F.SilkS")
		)
		(fp_line
			(start -1.143 -0.5588)
			(end -1.143 0.5588)
			(stroke
				(width 0.1)
				(type default)
			)
			(layer "F.SilkS")
		)
		(fp_line
			(start 1.143 -0.5588)
			(end -1.143 -0.5588)
			(stroke
				(width 0.1)
				(type default)
			)
			(layer "F.SilkS")
		)
		(fp_poly
			(pts
				(xy -1.143 0.5588) (xy 1.143 0.5588) (xy 1.143 -0.5588) (xy -1.143 -0.5588)
			)
			(stroke
				(width 0)
				(type default)
			)
			(fill no)
			(layer "F.CrtYd")
		)
		(fp_line
			(start -0.508 0.3048)
			(end 0.508 0.3048)
			(stroke
				(width 0.1)
				(type default)
			)
			(layer "F.Fab")
		)
		(fp_line
			(start 0.508 0.3048)
			(end 0.508 -0.3048)
			(stroke
				(width 0.1)
				(type default)
			)
			(layer "F.Fab")
		)
		(fp_line
			(start -0.508 -0.3048)
			(end -0.508 0.3048)
			(stroke
				(width 0.1)
				(type default)
			)
			(layer "F.Fab")
		)
		(fp_line
			(start 0.508 -0.3048)
			(end -0.508 -0.3048)
			(stroke
				(width 0.1)
				(type default)
			)
			(layer "F.Fab")
		)
		(pad "1" smd rect
			(at -0.5334 0 270)
			(size 0.7112 0.6096)
			(layers "F.Cu" "F.Mask" "F.Paste")
			(net "ANT4_OUT")
		)
		(pad "2" smd rect
			(at 0.5334 0 270)
			(size 0.7112 0.6096)
			(layers "F.Cu" "F.Mask" "F.Paste")
			(net "UNNAMED_12_74HCT2G125DPTSSOP8_3")
		)
		(zone
			(layer "F.Cu")
			(hatch none 0.5)
			(connect_pads
				(clearance 0)
			)
			(min_thickness 0.25)
			(keepout
				(tracks not_allowed)
				(vias allowed)
				(pads allowed)
				(copperpour not_allowed)
				(footprints allowed)
			)
			(placement
				(enabled no)
				(sheetname "")
			)
			(fill
				(thermal_gap 0.5)
				(thermal_bridge_width 0.5)
				(island_removal_mode 0)
			)
			(polygon
				(pts
					(xy 13.2842 -23.0632) (xy 13.2842 -22.9108) (xy 13.8938 -22.9108) (xy 13.8938 -23.0632)
				)
			)
		)
		(zone
			(layer "F.Cu")
			(hatch none 0.5)
			(connect_pads
				(clearance 0)
			)
			(min_thickness 0.25)
			(keepout
				(tracks allowed)
				(vias not_allowed)
				(pads allowed)
				(copperpour not_allowed)
				(footprints allowed)
			)
			(placement
				(enabled no)
				(sheetname "")
			)
			(fill
				(thermal_gap 0.5)
				(thermal_bridge_width 0.5)
				(island_removal_mode 0)
			)
			(polygon
				(pts
					(xy 13.2842 -23.0632) (xy 13.2842 -22.9108) (xy 13.8938 -22.9108) (xy 13.8938 -23.0632)
				)
			)
		)
	)
	(footprint ""
		(layer "F.Cu")
		(at 84.328 -76.581 90)
		(property "Reference" "TP1"
			(at 1.5875 -0.08763 90)
			(unlocked yes)
			(layer "F.SilkS")
			(effects
				(font
					(size 0.7874 0.5842)
					(thickness 0.1524)
				)
				(justify left)
			)
		)
		(property "Value" ""
			(at 0 0 90)
			(layer "F.Fab")
			(effects
				(font
					(size 1.27 1.27)
				)
			)
		)
		(property "Device Type" "TP_PIONT-TP010CT020B030_PTH-TPA"
			(at -1.341882 0.996696 90)
			(unlocked yes)
			(layer "F.Fab")
			(hide yes)
			(effects
				(font
					(size 0.7874 0.5842)
					(thickness 0.1524)
				)
				(justify left)
			)
		)
		(duplicate_pad_numbers_are_jumpers no)
		(fp_poly
			(pts
				(arc
					(start 0 0.889)
					(mid 0 -0.889)
					(end 0 0.889)
				)
			)
			(stroke
				(width 0)
				(type default)
			)
			(fill no)
			(layer "B.CrtYd")
		)
		(fp_poly
			(pts
				(arc
					(start 0 0.889)
					(mid 0 -0.889)
					(end 0 0.889)
				)
			)
			(stroke
				(width 0)
				(type default)
			)
			(fill no)
			(layer "F.CrtYd")
		)
		(pad "1" thru_hole circle
			(at 0 0 90)
			(size 0.508 0.508)
			(drill 0.254)
			(layers "*.Cu" "*.Mask")
			(remove_unused_layers no)
			(net "BNO080_EVN_SDA")
			(clearance 0.1016)
			(padstack
				(mode front_inner_back)
				(layer "Inner"
					(shape circle)
					(size 0.508 0.508)
					(clearance 0.1016)
				)
				(layer "B.Cu"
					(shape circle)
					(size 0.762 0.762)
					(clearance -0.0254)
				)
			)
		)
	)
)
